# S9S_MB_2U (Grand Teton) — schematic netlist excerpt (pin names and nets, part order shuffled) for the footprints in the layout excerpt that follows; sources: Cadence DE-HDL packaged netlist, KiCad conversion of 03242023_DA0F0TMBIJ0_F0T_Motherboard_J_brd_V01_OCP.brd

PR1390  Q_RES  49.9 1% CHIP  pkg 0402LF  page 278 : A = P12V_AUX_CPU0_DIMM_ISEN_N ; B = PVCCD_HV_CPU0_ISENSE_N
R1243  Q_RES  249 1% CHIP  pkg 0402LF  page 117 : A = H_PMAX_TRIGGER_IO_CPU1 ; B = GND
R3633  Q_RES  0.01 1% CHIP  pkg 2512LF  page 172 : A = P3V3_OCP_V3_2 ; B = P3V3_OCP_V3_2_R

(kicad_pcb
	(version 20260206)
	(generator "pcbnew")
	(generator_version "10.0")
	(general
		(thickness 1.6)
		(legacy_teardrops no)
	)
	(paper "A4")
	(title_block
		(title "03242023_DA0F0TMBIJ0_F0T_Motherboard_J_brd_V01_OCP.brd")
		(comment 1 "Grand Teton / footprints 4161-4163 of 6105")
	)
	(layers
		(0 "F.Cu" signal "TOP")
		(4 "In1.Cu" signal "GND")
		(6 "In2.Cu" signal "IN1")
		(8 "In3.Cu" signal "GND1")
		(10 "In4.Cu" signal "IN2")
		(12 "In5.Cu" signal "GND2")
		(14 "In6.Cu" signal "IN3")
		(16 "In7.Cu" signal "GND3")
		(18 "In8.Cu" signal "VCC")
		(20 "In9.Cu" signal "VCC1")
		(22 "In10.Cu" signal "GND4")
		(24 "In11.Cu" signal "IN4")
		(26 "In12.Cu" signal "GND5")
		(28 "In13.Cu" signal "IN5")
		(30 "In14.Cu" signal "GND6")
		(32 "In15.Cu" signal "IN6")
		(34 "In16.Cu" signal "GND7")
		(2 "B.Cu" signal "BOTTOM")
		(9 "F.Adhes" user "F.Adhesive")
		(11 "B.Adhes" user "B.Adhesive")
		(13 "F.Paste" user "Package Geometry/Pastemask Top")
		(15 "B.Paste" user "Package Geometry/Pastemask Bottom")
		(5 "F.SilkS" user "Ref Des/Silkscreen Top")
		(7 "B.SilkS" user "Ref Des/Silkscreen Bottom")
		(1 "F.Mask" user "Board Geometry/Soldermask Top")
		(3 "B.Mask" user "Board Geometry/Soldermask Bottom")
		(17 "Dwgs.User" user "User.Drawings")
		(19 "Cmts.User" user "User.Comments")
		(21 "Eco1.User" user "User.Eco1")
		(23 "Eco2.User" user "User.Eco2")
		(25 "Edge.Cuts" user "Board Geometry/Outline")
		(27 "Margin" user)
		(31 "F.CrtYd" user "Package Geometry/Place Bound Top")
		(29 "B.CrtYd" user "Package Geometry/Place Bound Bottom")
		(35 "F.Fab" user "Ref Des/Assembly Top")
		(33 "B.Fab" user "Ref Des/Assembly Bottom")
	)
	(footprint ""
		(layer "B.Cu")
		(at 426.892212 -121.685812 180)
		(property "Reference" "PR1390"
			(at 0 0 0)
			(layer "B.SilkS")
			(hide yes)
			(effects
				(font
					(size 1.27 1.27)
				)
				(justify mirror)
			)
		)
		(property "Value" ""
			(at 0 0 0)
			(layer "B.Fab")
			(effects
				(font
					(size 1.27 1.27)
				)
				(justify mirror)
			)
		)
		(duplicate_pad_numbers_are_jumpers no)
		(fp_line
			(start 0.7874 0.4064)
			(end 0.7874 -0.4064)
			(stroke
				(width 0.1524)
				(type default)
			)
			(layer "B.SilkS")
		)
		(fp_line
			(start 0.7874 -0.4064)
			(end -0.7874 -0.4064)
			(stroke
				(width 0.1524)
				(type default)
			)
			(layer "B.SilkS")
		)
		(fp_line
			(start -0.7874 0.4064)
			(end 0.7874 0.4064)
			(stroke
				(width 0.1524)
				(type default)
			)
			(layer "B.SilkS")
		)
		(fp_line
			(start -0.7874 -0.4064)
			(end -0.7874 0.4064)
			(stroke
				(width 0.1524)
				(type default)
			)
			(layer "B.SilkS")
		)
		(fp_line
			(start 0.67945 0.3048)
			(end 0.67945 -0.305054)
			(stroke
				(width 0.1)
				(type default)
			)
			(layer "B.Fab")
		)
		(fp_line
			(start 0.67945 -0.305054)
			(end 0.12065 -0.305054)
			(stroke
				(width 0.1)
				(type default)
			)
			(layer "B.Fab")
		)
		(fp_line
			(start 0.12065 0.3048)
			(end 0.67945 0.3048)
			(stroke
				(width 0.1)
				(type default)
			)
			(layer "B.Fab")
		)
		(fp_line
			(start 0.12065 0.2794)
			(end 0.12065 0.3048)
			(stroke
				(width 0.1)
				(type default)
			)
			(layer "B.Fab")
		)
		(fp_line
			(start 0.12065 -0.2794)
			(end -0.12065 -0.2794)
			(stroke
				(width 0.1)
				(type default)
			)
			(layer "B.Fab")
		)
		(fp_line
			(start 0.12065 -0.305054)
			(end 0.12065 -0.2794)
			(stroke
				(width 0.1)
				(type default)
			)
			(layer "B.Fab")
		)
		(fp_line
			(start -0.120396 0.3048)
			(end -0.120396 0.2794)
			(stroke
				(width 0.1)
				(type default)
			)
			(layer "B.Fab")
		)
		(fp_line
			(start -0.120396 0.2794)
			(end 0.12065 0.2794)
			(stroke
				(width 0.1)
				(type default)
			)
			(layer "B.Fab")
		)
		(fp_line
			(start -0.12065 -0.2794)
			(end -0.12065 -0.3048)
			(stroke
				(width 0.1)
				(type default)
			)
			(layer "B.Fab")
		)
		(fp_line
			(start -0.12065 -0.3048)
			(end -0.67945 -0.3048)
			(stroke
				(width 0.1)
				(type default)
			)
			(layer "B.Fab")
		)
		(fp_line
			(start -0.67945 0.3048)
			(end -0.120396 0.3048)
			(stroke
				(width 0.1)
				(type default)
			)
			(layer "B.Fab")
		)
		(fp_line
			(start -0.67945 -0.3048)
			(end -0.67945 0.3048)
			(stroke
				(width 0.1)
				(type default)
			)
			(layer "B.Fab")
		)
		(pad "1" smd circle
			(at 0.40005 0)
			(size 0 0)
			(layers "B.Cu" "B.Mask" "B.Paste")
			(net "P12V_AUX_CPU0_DIMM_ISEN_N")
		)
		(pad "2" smd circle
			(at -0.40005 0)
			(size 0 0)
			(layers "B.Cu" "B.Mask" "B.Paste")
			(net "PVCCD_HV_CPU0_ISENSE_N")
		)
	)
	(footprint ""
		(layer "B.Cu")
		(at 70.012306 -219.823538 90)
		(property "Reference" "R1243"
			(at 0 0 90)
			(layer "B.SilkS")
			(hide yes)
			(effects
				(font
					(size 1.27 1.27)
				)
				(justify mirror)
			)
		)
		(property "Value" ""
			(at 0 0 90)
			(layer "B.Fab")
			(effects
				(font
					(size 1.27 1.27)
				)
				(justify mirror)
			)
		)
		(duplicate_pad_numbers_are_jumpers no)
		(fp_line
			(start 0.7874 -0.4064)
			(end -0.7874 -0.4064)
			(stroke
				(width 0.1524)
				(type default)
			)
			(layer "B.SilkS")
		)
		(fp_line
			(start -0.7874 -0.4064)
			(end -0.7874 0.4064)
			(stroke
				(width 0.1524)
				(type default)
			)
			(layer "B.SilkS")
		)
		(fp_line
			(start 0.7874 0.4064)
			(end 0.7874 -0.4064)
			(stroke
				(width 0.1524)
				(type default)
			)
			(layer "B.SilkS")
		)
		(fp_line
			(start -0.7874 0.4064)
			(end 0.7874 0.4064)
			(stroke
				(width 0.1524)
				(type default)
			)
			(layer "B.SilkS")
		)
		(fp_line
			(start 0.67945 -0.305054)
			(end 0.12065 -0.305054)
			(stroke
				(width 0.1)
				(type default)
			)
			(layer "B.Fab")
		)
		(fp_line
			(start 0.12065 -0.305054)
			(end 0.12065 -0.2794)
			(stroke
				(width 0.1)
				(type default)
			)
			(layer "B.Fab")
		)
		(fp_line
			(start -0.12065 -0.3048)
			(end -0.67945 -0.3048)
			(stroke
				(width 0.1)
				(type default)
			)
			(layer "B.Fab")
		)
		(fp_line
			(start -0.67945 -0.3048)
			(end -0.67945 0.3048)
			(stroke
				(width 0.1)
				(type default)
			)
			(layer "B.Fab")
		)
		(fp_line
			(start 0.12065 -0.2794)
			(end -0.12065 -0.2794)
			(stroke
				(width 0.1)
				(type default)
			)
			(layer "B.Fab")
		)
		(fp_line
			(start -0.12065 -0.2794)
			(end -0.12065 -0.3048)
			(stroke
				(width 0.1)
				(type default)
			)
			(layer "B.Fab")
		)
		(fp_line
			(start 0.12065 0.2794)
			(end 0.12065 0.3048)
			(stroke
				(width 0.1)
				(type default)
			)
			(layer "B.Fab")
		)
		(fp_line
			(start -0.120396 0.2794)
			(end 0.12065 0.2794)
			(stroke
				(width 0.1)
				(type default)
			)
			(layer "B.Fab")
		)
		(fp_line
			(start 0.67945 0.3048)
			(end 0.67945 -0.305054)
			(stroke
				(width 0.1)
				(type default)
			)
			(layer "B.Fab")
		)
		(fp_line
			(start 0.12065 0.3048)
			(end 0.67945 0.3048)
			(stroke
				(width 0.1)
				(type default)
			)
			(layer "B.Fab")
		)
		(fp_line
			(start -0.120396 0.3048)
			(end -0.120396 0.2794)
			(stroke
				(width 0.1)
				(type default)
			)
			(layer "B.Fab")
		)
		(fp_line
			(start -0.67945 0.3048)
			(end -0.120396 0.3048)
			(stroke
				(width 0.1)
				(type default)
			)
			(layer "B.Fab")
		)
		(pad "1" smd circle
			(at 0.40005 0 270)
			(size 0 0)
			(layers "B.Cu" "B.Mask" "B.Paste")
			(net "H_PMAX_TRIGGER_IO_CPU1")
		)
		(pad "2" smd circle
			(at -0.40005 0 270)
			(size 0 0)
			(layers "B.Cu" "B.Mask" "B.Paste")
			(net "GND")
		)
	)
	(footprint ""
		(layer "B.Cu")
		(at 81.422494 -45.785786 -90)
		(property "Reference" "R3633"
			(at 0 0 90)
			(layer "B.SilkS")
			(hide yes)
			(effects
				(font
					(size 1.27 1.27)
				)
				(justify mirror)
			)
		)
		(property "Value" ""
			(at 0 0 90)
			(layer "B.Fab")
			(effects
				(font
					(size 1.27 1.27)
				)
				(justify mirror)
			)
		)
		(duplicate_pad_numbers_are_jumpers no)
		(fp_line
			(start -4.0386 1.7526)
			(end 4.0386 1.7526)
			(stroke
				(width 0.1524)
				(type default)
			)
			(layer "B.SilkS")
		)
		(fp_line
			(start 4.0386 1.7526)
			(end 4.0386 -1.7526)
			(stroke
				(width 0.1524)
				(type default)
			)
			(layer "B.SilkS")
		)
		(fp_line
			(start -4.0386 -1.7526)
			(end -4.0386 1.7526)
			(stroke
				(width 0.1524)
				(type default)
			)
			(layer "B.SilkS")
		)
		(fp_line
			(start 4.0386 -1.7526)
			(end -4.0386 -1.7526)
			(stroke
				(width 0.1524)
				(type default)
			)
			(layer "B.SilkS")
		)
		(fp_line
			(start -4.0386 1.7526)
			(end 4.0386 1.7526)
			(stroke
				(width 0.1)
				(type default)
			)
			(layer "B.Fab")
		)
		(fp_line
			(start 4.0386 1.7526)
			(end 4.0386 -1.7526)
			(stroke
				(width 0.1)
				(type default)
			)
			(layer "B.Fab")
		)
		(fp_line
			(start -4.0386 -1.7526)
			(end -4.0386 1.7526)
			(stroke
				(width 0.1)
				(type default)
			)
			(layer "B.Fab")
		)
		(fp_line
			(start 4.0386 -1.7526)
			(end -4.0386 -1.7526)
			(stroke
				(width 0.1)
				(type default)
			)
			(layer "B.Fab")
		)
		(pad "1" smd rect
			(at 3.1115 0 90)
			(size 1.524 3.2004)
			(layers "B.Cu" "B.Mask" "B.Paste")
			(net "P3V3_OCP_V3_2")
		)
		(pad "2" smd rect
			(at -3.1115 0 90)
			(size 1.524 3.2004)
			(layers "B.Cu" "B.Mask" "B.Paste")
			(net "P3V3_OCP_V3_2_R")
		)
	)
)
